FILE_TYPE = MULTI_PHYS_TABLE;

PART 'SCHOTTKY_12'

{========================================================================================}
:VALUE                     | PART_TYPE | MATERIAL | PART_NUMBER    = STANDARD        | LIFECYCLE      | PART_NUMBER   | JEDEC_TYPE        | DESCRIPTION                                | MANUFTR | MANUF_PN          | RD_CMPLS_LVL | CMPLS_LVL | CLASS | DIP_SMD | FP_ECN      | FROM_PJ          | DATA                        | EE_CHECK_LIST | STATUS | PSL | PREFERENCE | CREATOR | CREATEDAY  ;
{========================================================================================}
 'SMCJ13A-13-F(13V/1500W)' | 'SMLF'    | 'IC'     | 'BC0CJ13AZ00'(!) = 'End of Design' | 'End of Life'  | 'BC0CJ13AZ00' |'D_SMCJ170_EOL'| 'DIODE SMD SMCJ13A-13-F(13V,1500W,SMC)'    | 'DDS'   | 'SMCJ13A-13-F'    | 'EP(V1)'     | ''        | 'IC'  | ''      | ''          | 'F03U-WENLUNG'   | 'DDS_SMCJ170cA.pdf'         | ''            | ''     | ''  | ''         | ''      | '20120509'
 'SMCJ13A-13-F(13V/1500W)' | 'SMLF'    | 'EMPTY'  | 'BC0CJ13AZ00'(!) = 'End of Design' | 'End of Life'  | 'BC0CJ13AZ00' |'D_SMCJ170_EOL'| 'DIODE SMD SMCJ13A-13-F(13V,1500W,SMC)'    | 'DDS'   | 'SMCJ13A-13-F'    | 'EP(V1)'     | ''        | 'IC'  | ''      | ''          | 'F03U-WENLUNG'   | 'DDS_SMCJ170cA.pdf'         | ''            | ''     | ''  | ''         | ''      | '20120509'
 'DFLS1100-7'              | 'SMLF'    | 'IC'     | 'BCLS1100Z00'(!) = 'End of Design' | 'Comp-Approve' | 'BCLS1100Z00' |'POWERDI123'| 'DIODE SMD DFLS1100-7 (100V,1A)SCHOTKY HF' | 'DDS'   | 'DFLS1100-7'      | 'EP(V1)'     | 'EP(V1)'  | 'IC'  | ''      | ''          | 'T2L-CHEESE'     | 'DFLS1100.pdf'              | ''            | ''     | ''  | ''         | ''      | '20120305'
 'DFLS1100-7'              | 'SMLF'    | 'EMPTY'  | 'BCLS1100Z00'(!) = 'End of Design' | 'Comp-Approve' | 'BCLS1100Z00' |'POWERDI123'| 'DIODE SMD DFLS1100-7 (100V,1A)SCHOTKY HF' | 'DDS'   | 'DFLS1100-7'      | 'EP(V1)'     | 'EP(V1)'  | 'IC'  | ''      | ''          | 'T2L-CHEESE'     | 'DFLS1100.pdf'              | ''            | ''     | ''  | ''         | ''      | '20120305'
 'B0530W-7-F'              | 'SMLF'    | 'IC'     | 'BC000530Z25'(!) = 'End of Design' | 'Comp-Approve'   | 'BC000530Z25' |'SOD123XC'| 'DIODE SCHOTTKY B0530W-7-F(SOD-123)'       | 'DDS'   | 'B0530W-7-F'      | 'EP'         | 'EP(V1)'  | 'IC'  | ''      | ''          | 'S1N- SIMON'     | 'DDS_B0530W-7-F.pdf'        | ''            | ''     | ''  | ''         | ''      | '20120618'
 'B0530W-7-F'              | 'SMLF'    | 'EMPTY'  | 'BC000530Z25'(!) = 'End of Design' | 'Comp-Approve'   | 'BC000530Z25' |'SOD123XC'| 'DIODE SCHOTTKY B0530W-7-F(SOD-123)'       | 'DDS'   | 'B0530W-7-F'      | 'EP'         | 'EP(V1)'  | 'IC'  | ''      | ''          | 'S1N- SIMON'     | 'DDS_B0530W-7-F.pdf'        | ''            | ''     | ''  | ''         | ''      | '20120618'
 'RB500V-40G'              | 'SMLF'    | 'IC'     | 'BCRB500VZ00'(!) = ''              | ''             | 'BCRB500VZ00' |'SOD323'| 'DIODE SMD RB500V-40G(40V0.1A,SCHOTTKY)'   | 'ROH'   | 'RB500V-40GTE-17' | 'EP(V1)'     | 'EP(V1)'  | 'IC'  | ''      | ''          | 'S1D-OZ'         | 'ROH_RB500V-40.pdf'         | ''            | ''     | ''  | ''         | ''      | '20120918'
 'RB500V-40G'              | 'SMLF'    | 'EMPTY'  | 'BCRB500VZ00'(!) = ''              | ''             | 'BCRB500VZ00' |'SOD323'| 'DIODE SMD RB500V-40G(40V0.1A,SCHOTTKY)'   | 'ROH'   | 'RB500V-40GTE-17' | 'EP(V1)'     | 'EP(V1)'  | 'IC'  | ''      | ''          | 'S1D-OZ'         | 'ROH_RB500V-40.pdf'         | ''            | ''     | ''  | ''         | ''      | '20120918'
 'RB500V-40'               | 'SMLF'    | 'IC'     | 'BCRB500VZ29'(!) = ''              | ''             | 'BCRB500VZ29' |'SOD323XF'| 'DIODE SMD RB500V-40(40V,0.1A,SCHOTTKY)'   | 'PJT'   | 'RB500V-40'       | 'EP(V1)'     | 'EP(V1)'  | 'IC'  | ''      | ''          | 'S1D-OZ'         | 'PJT_RB500V-40.pdf'         | ''            | ''     | ''  | ''         | ''      | '20120918'
 'RB500V-40'               | 'SMLF'    | 'EMPTY'  | 'BCRB500VZ29'(!) = ''              | ''             | 'BCRB500VZ29' |'SOD323XF'| 'DIODE SMD RB500V-40(40V,0.1A,SCHOTTKY)'   | 'PJT'   | 'RB500V-40'       | 'EP(V1)'     | 'EP(V1)'  | 'IC'  | ''      | ''          | 'S1D-OZ'         | 'PJT_RB500V-40.pdf'         | ''            | ''     | ''  | ''         | ''      | '20120918'
 'SDM10K45-7-F'            | 'SMLF'    | 'IC'     | 'BC010K45004'(!) = 'End of Design' | 'Comp-Approve' | 'BC010K45004' |'SOD323'| 'DIODE SMD SDM10K45-7-F(40V.0.1A)'         | 'DDS'   | 'SDM10K45-7-F'    | 'EP(V1)'     | 'EP(V1)'  | 'IC'  | ''      | ''          | 'T2B-KC'         | 'SDM10K45-7-F.pdf'          | ''            | ''     | ''  | ''         | ''      | '20120918'
 'SDM10K45-7-F'            | 'SMLF'    | 'EMPTY'  | 'BC010K45004'(!) = 'End of Design' | 'Comp-Approve' | 'BC010K45004' |'SOD323'| 'DIODE SMD SDM10K45-7-F(40V.0.1A)'         | 'DDS'   | 'SDM10K45-7-F'    | 'EP(V1)'     | 'EP(V1)'  | 'IC'  | ''      | ''          | 'T2B-KC'         | 'SDM10K45-7-F.pdf'          | ''            | ''     | ''  | ''         | ''      | '20120918'
 'B540C-13-F'              | 'SMLF'    | 'IC'     | 'BC0B540CZ19'(!) = ''              | ''             | 'BC0B540CZ19' |'D2723_SMCXB'| 'DIODE SCHOTTKY B540C-13-F(40V,5A,SMC)'    | 'DDS'   | 'B540C-13-F'      | 'EP(V1)'     | 'EP(V1)'  | 'IC'  | ''      | ''          | 'T6BB-KEN'       | 'DDS_B540C-13-F_rev6-2.pdf' | ''            | ''     | ''  | ''         | ''      | '20130620'
 'B540C-13-F'              | 'SMLF'    | 'EMPTY'  | 'BC0B540CZ19'(!) = ''              | ''             | 'BC0B540CZ19' |'D2723_SMCXB'| 'DIODE SCHOTTKY B540C-13-F(40V,5A,SMC)'    | 'DDS'   | 'B540C-13-F'      | 'EP(V1)'     | 'EP(V1)'  | 'IC'  | ''      | ''          | 'T6BB-KEN'       | 'DDS_B540C-13-F_rev6-2.pdf' | ''            | ''     | ''  | ''         | ''      | '20130620'
 'SS14'                    | 'SMLF'    | 'IC'     | 'BC00SS14000'(!) = ''              | ''             | 'BC00SS14000' |'D2010'| 'DIODE SMD SS14(1A.40V.SCHOTTY)'           | 'PJT'   | 'SS14'            | ''           | 'EP'      | 'IC'  | ''      | 'D2010.doc' | 'K08-ERIC'       | 'PJT_SS12-S100.pdf'         | ''            | ''     | ''  | ''         | ''      | '20130628'
 'SS14'                    | 'SMLF'    | 'EMPTY'  | 'BC00SS14000'(!) = ''              | ''             | 'BC00SS14000' |'D2010'| 'DIODE SMD SS14(1A.40V.SCHOTTY)'           | 'PJT'   | 'SS14'            | ''           | 'EP'      | 'IC'  | ''      | 'D2010.doc' | 'K08-ERIC'       | 'PJT_SS12-S100.pdf'         | ''            | ''     | ''  | ''         | ''      | '20130628'
 'DFLT5V0A-7'              | 'SMLF'    | 'IC'     | 'BCLT5V0AZ00'(!) = ''              | ''             | 'BCLT5V0AZ00' |'POWERDI123'| 'DIODE SMD DFLT5V0A-7(5V,24.5A,208)'       | 'DDS'   | 'DFLT5V0A-7'      | 'EP(V1)'     | 'EP(V1)'  | 'IC'  | ''      | ''          | 'F03B-CHIH-FENG' | 'DDS_DS30581-rev7-2.pdf'    | ''            | ''     | ''  | ''         | ''      | '20130628'
 'DFLT5V0A-7'              | 'SMLF'    | 'EMPTY'  | 'BCLT5V0AZ00'(!) = ''              | ''             | 'BCLT5V0AZ00' |'POWERDI123'| 'DIODE SMD DFLT5V0A-7(5V,24.5A,208)'       | 'DDS'   | 'DFLT5V0A-7'      | 'EP(V1)'     | 'EP(V1)'  | 'IC'  | ''      | ''          | 'F03B-CHIH-FENG' | 'DDS_DS30581-rev7-2.pdf'    | ''            | ''     | ''  | ''         | ''      | '20130628'
 'DFLT13A-7'               | 'SMLF'    | 'IC'     | 'BC0LT13AZ00'(!) = ''              | ''             | 'BC0LT13AZ00' |'POWERDI123'| 'DIODE SMD DFLT13A-7(13V,10.5A,1W)'        | 'DDS'   | 'DFLT13A-7'       | 'EP(V1)'     | ''        | 'IC'  | ''      | ''          | 'F03B-CHIH-FENG' | 'DDS_DS30581-rev7-2.pdf'    | ''            | ''     | ''  | ''         | ''      | '20130628'
 'DFLT13A-7'               | 'SMLF'    | 'EMPTY'  | 'BC0LT13AZ00'(!) = ''              | ''             | 'BC0LT13AZ00' |'POWERDI123'| 'DIODE SMD DFLT13A-7(13V,10.5A,1W)'        | 'DDS'   | 'DFLT13A-7'       | 'EP(V1)'     | ''        | 'IC'  | ''      | ''          | 'F03B-CHIH-FENG' | 'DDS_DS30581-rev7-2.pdf'    | ''            | ''     | ''  | ''         | ''      | '20130628'
 'B0530WS7F'               | 'SMLF'    | 'IC'     | 'BC000530Z41'(!) = 'End of Design' | 'Comp-Approve' | 'BC000530Z41' |'SOD323XB'| 'DIODE SMD B0530WS-7-F(30V,0.5A)SOD-323'   | 'DDS'   | 'B0530WS-7-F'     | 'EP'         | 'EP(V1)'  | 'IC'  | ''      | ''          | 'T2R-GAVEN'      | 'B0530WS-7-F.pdf'           | ''            | ''     | ''  | ''         | ''      | '20140704'
 'B0530WS7F'               | 'SMLF'    | 'EMPTY'  | 'BC000530Z41'(!) = 'End of Design' | 'Comp-Approve' | 'BC000530Z41' |'SOD323XB'| 'DIODE SMD B0530WS-7-F(30V,0.5A)SOD-323'   | 'DDS'   | 'B0530WS-7-F'     | 'EP'         | 'EP(V1)'  | 'IC'  | ''      | ''          | 'T2R-GAVEN'      | 'B0530WS-7-F.pdf'           | ''            | ''     | ''  | ''         | ''      | '20140704'
 '1N5819HW'                | 'SMLF'    | 'IC'     | 'BC005819Z40'(!) = 'End of Design' | 'Comp-Approve' | 'BC005819Z40' |'SOD123'| 'DIODE SMD 1N5819HW-7-F(40V.1A.SOD123)'    | 'DDS'   | '1N5819HW-7-F'    | ''           | 'EP'      | 'IC'  | ''      | ''          | 'T2H-WADE'       | 'DDS_1N5819HW.pdf'          | ''            | ''     | ''  | ''         | ''      | '20151228'
 '1N5819HW'                | 'SMLF'    | 'EMPTY'  | 'BC005819Z40'(!) = 'End of Design' | 'Comp-Approve' | 'BC005819Z40' |'SOD123'| 'DIODE SMD 1N5819HW-7-F(40V.1A.SOD123)'    | 'DDS'   | '1N5819HW-7-F'    | ''           | 'EP'      | 'IC'  | ''      | ''          | 'T2H-WADE'       | 'DDS_1N5819HW.pdf'          | ''            | ''     | ''  | ''         | ''      | '20151228'
 'SBA130Q'                 | 'SMLF'    | 'IC'     | 'BCSBA130Z00'(!) = ''              | ''             | 'BCSBA130Z00' |'DFN1610-2_1-6X1'| 'DIODE SMD SBA130Q(30V,1A,SCHOTTKY)'       | 'PJT'   | 'SBA130Q'         | 'EP(V1)'     | ''        | 'IC'  | ''      | ''          | 'S6A-HANK'       | 'PJT_SBA130Q.pdf'           | ''            | ''     | ''  | ''         | ''      | '20180508'
 'SBA130Q'                 | 'SMLF'    | 'EMPTY'  | 'BCSBA130Z00'(!) = ''              | ''             | 'BCSBA130Z00' |'DFN1610-2_1-6X1'| 'DIODE SMD SBA130Q(30V,1A,SCHOTTKY)'       | 'PJT'   | 'SBA130Q'         | 'EP(V1)'     | ''        | 'IC'  | ''      | ''          | 'S6A-HANK'       | 'PJT_SBA130Q.pdf'           | ''            | ''     | ''  | ''         | ''      | '20180508'
 'BAT46W-7-F'              | 'SMLF'    | 'IC'     | 'BCBAT46W000'(!) = 'End of Design' | 'Comp-Approve' | 'BCBAT46W000' |'SOD123XC'| 'DIODE SMD BAT46W-7-F(100V,150MA,SCHOTTKY' | 'DDS'   | 'BAT46W-7-F'      | 'EP(V1)'     | 'EP(V1)'  | 'IC'  | ''      | ''          | 'T2L-CHEESE'     | 'DDS_BAT46W-7-F.pdf'        | ''            | ''     | ''  | ''         | ''      | '20190626'
 'BAT46W-7-F'              | 'SMLF'    | 'EMPTY'  | 'BCBAT46W000'(!) = 'End of Design' | 'Comp-Approve' | 'BCBAT46W000' |'SOD123XC'| 'DIODE SMD BAT46W-7-F(100V,150MA,SCHOTTKY' | 'DDS'   | 'BAT46W-7-F'      | 'EP(V1)'     | 'EP(V1)'  | 'IC'  | ''      | ''          | 'T2L-CHEESE'     | 'DDS_BAT46W-7-F.pdf'        | ''            | ''     | ''  | ''         | ''      | '20190626'
 'SMCJ12A-13-F'            | 'SMLF'    | 'IC'     | 'BC0CJ12AZ00'(!) = ''              | ''               | 'BC0CJ12AZ00' |'D_SMCJ170'| 'DIODE SMD SMCJ12A-13-F(12V,1500W,SMC)'    | 'DDS'   | 'SMCJ12A-13-F'    | 'EU'         | 'EU'      | 'IC'  | ''      | ''          | 'S6YQ-SIMON'     | 'DDS_SMCJ12A-13-F.pdf'      | ''            | ''     | ''  | ''         | ''      | '20201230'
 'SMCJ12A-13-F'            | 'SMLF'    | 'EMPTY'  | 'BC0CJ12AZ00'(!) = ''              | ''               | 'BC0CJ12AZ00' |'D_SMCJ170'| 'DIODE SMD SMCJ12A-13-F(12V,1500W,SMC)'    | 'DDS'   | 'SMCJ12A-13-F'    | 'EU'         | 'EU'      | 'IC'  | ''      | ''          | 'S6YQ-SIMON'     | 'DDS_SMCJ12A-13-F.pdf'      | ''            | ''     | ''  | ''         | ''      | '20201230'

END_PART

END.

